# SCM (Grand Teton) — schematic netlist excerpt (pin names and nets, part order shuffled) for the footprints in the layout excerpt that follows; sources: Cadence DE-HDL packaged netlist, KiCad conversion of 12092022_DA0F0TMDCD0_F0T_Management_Board_D_brd_V3_OCP.brd

C94  Q_CAP  0.1UF 25V 10% X7R  pkg 0402  page 16 : A = P3V3_AUX ; B = GND
R120  Q_RES  33.2 1% CHIP  pkg 0402LF  page 12 : A = RST_BMC_LPC_ESPI_N ; B = RST_ESPI_LPC_BMC_N

(kicad_pcb
	(version 20260206)
	(generator "pcbnew")
	(generator_version "10.0")
	(general
		(thickness 1.6)
		(legacy_teardrops no)
	)
	(paper "A4")
	(title_block
		(title "12092022_DA0F0TMDCD0_F0T_Management_Board_D_brd_V3_OCP.brd")
		(comment 1 "Grand Teton / footprints 899-900 of 1440")
	)
	(layers
		(0 "F.Cu" signal "TOP")
		(4 "In1.Cu" signal "GND")
		(6 "In2.Cu" signal "IN1")
		(8 "In3.Cu" signal "GND1")
		(10 "In4.Cu" signal "IN2")
		(12 "In5.Cu" signal "VCC")
		(14 "In6.Cu" signal "VCC1")
		(16 "In7.Cu" signal "IN3")
		(18 "In8.Cu" signal "GND2")
		(20 "In9.Cu" signal "IN4")
		(22 "In10.Cu" signal "GND3")
		(2 "B.Cu" signal "BOTTOM")
		(9 "F.Adhes" user "F.Adhesive")
		(11 "B.Adhes" user "B.Adhesive")
		(13 "F.Paste" user "Package Geometry/Pastemask Top")
		(15 "B.Paste" user "Package Geometry/Pastemask Bottom")
		(5 "F.SilkS" user "Ref Des/Silkscreen Top")
		(7 "B.SilkS" user "Ref Des/Silkscreen Bottom")
		(1 "F.Mask" user "Board Geometry/Soldermask Top")
		(3 "B.Mask" user "Board Geometry/Soldermask Bottom")
		(17 "Dwgs.User" user "User.Drawings")
		(19 "Cmts.User" user "User.Comments")
		(21 "Eco1.User" user "User.Eco1")
		(23 "Eco2.User" user "User.Eco2")
		(25 "Edge.Cuts" user "Board Geometry/Outline")
		(27 "Margin" user)
		(31 "F.CrtYd" user "Package Geometry/Place Bound Top")
		(29 "B.CrtYd" user "Package Geometry/Place Bound Bottom")
		(35 "F.Fab" user "Ref Des/Assembly Top")
		(33 "B.Fab" user "Ref Des/Assembly Bottom")
	)
	(footprint ""
		(layer "B.Cu")
		(at 63.964058 -71.317612)
		(property "Reference" "R120"
			(at 0 0 0)
			(layer "B.SilkS")
			(hide yes)
			(effects
				(font
					(size 1.27 1.27)
				)
				(justify mirror)
			)
		)
		(property "Value" ""
			(at 0 0 0)
			(layer "B.Fab")
			(effects
				(font
					(size 1.27 1.27)
				)
				(justify mirror)
			)
		)
		(duplicate_pad_numbers_are_jumpers no)
		(fp_line
			(start -0.7874 -0.4064)
			(end -0.7874 0.4064)
			(stroke
				(width 0.1524)
				(type default)
			)
			(layer "B.SilkS")
		)
		(fp_line
			(start -0.7874 0.4064)
			(end 0.7874 0.4064)
			(stroke
				(width 0.1524)
				(type default)
			)
			(layer "B.SilkS")
		)
		(fp_line
			(start 0.7874 -0.4064)
			(end -0.7874 -0.4064)
			(stroke
				(width 0.1524)
				(type default)
			)
			(layer "B.SilkS")
		)
		(fp_line
			(start 0.7874 0.4064)
			(end 0.7874 -0.4064)
			(stroke
				(width 0.1524)
				(type default)
			)
			(layer "B.SilkS")
		)
		(fp_line
			(start -0.67945 -0.3048)
			(end -0.67945 0.3048)
			(stroke
				(width 0.1)
				(type default)
			)
			(layer "B.Fab")
		)
		(fp_line
			(start -0.67945 0.3048)
			(end -0.120396 0.3048)
			(stroke
				(width 0.1)
				(type default)
			)
			(layer "B.Fab")
		)
		(fp_line
			(start -0.12065 -0.3048)
			(end -0.67945 -0.3048)
			(stroke
				(width 0.1)
				(type default)
			)
			(layer "B.Fab")
		)
		(fp_line
			(start -0.12065 -0.2794)
			(end -0.12065 -0.3048)
			(stroke
				(width 0.1)
				(type default)
			)
			(layer "B.Fab")
		)
		(fp_line
			(start -0.120396 0.2794)
			(end 0.12065 0.2794)
			(stroke
				(width 0.1)
				(type default)
			)
			(layer "B.Fab")
		)
		(fp_line
			(start -0.120396 0.3048)
			(end -0.120396 0.2794)
			(stroke
				(width 0.1)
				(type default)
			)
			(layer "B.Fab")
		)
		(fp_line
			(start 0.12065 -0.305054)
			(end 0.12065 -0.2794)
			(stroke
				(width 0.1)
				(type default)
			)
			(layer "B.Fab")
		)
		(fp_line
			(start 0.12065 -0.2794)
			(end -0.12065 -0.2794)
			(stroke
				(width 0.1)
				(type default)
			)
			(layer "B.Fab")
		)
		(fp_line
			(start 0.12065 0.2794)
			(end 0.12065 0.3048)
			(stroke
				(width 0.1)
				(type default)
			)
			(layer "B.Fab")
		)
		(fp_line
			(start 0.12065 0.3048)
			(end 0.67945 0.3048)
			(stroke
				(width 0.1)
				(type default)
			)
			(layer "B.Fab")
		)
		(fp_line
			(start 0.67945 -0.305054)
			(end 0.12065 -0.305054)
			(stroke
				(width 0.1)
				(type default)
			)
			(layer "B.Fab")
		)
		(fp_line
			(start 0.67945 0.3048)
			(end 0.67945 -0.305054)
			(stroke
				(width 0.1)
				(type default)
			)
			(layer "B.Fab")
		)
		(pad "1" smd circle
			(at 0.40005 0 180)
			(size 0 0)
			(layers "B.Cu" "B.Mask" "B.Paste")
			(net "RST_BMC_LPC_ESPI_N")
		)
		(pad "2" smd circle
			(at -0.40005 0 180)
			(size 0 0)
			(layers "B.Cu" "B.Mask" "B.Paste")
			(net "RST_ESPI_LPC_BMC_N")
		)
	)
	(footprint ""
		(layer "B.Cu")
		(at 52.024534 -54.93258 180)
		(property "Reference" "C94"
			(at 0 0 0)
			(layer "B.SilkS")
			(hide yes)
			(effects
				(font
					(size 1.27 1.27)
				)
				(justify mirror)
			)
		)
		(property "Value" ""
			(at 0 0 0)
			(layer "B.Fab")
			(effects
				(font
					(size 1.27 1.27)
				)
				(justify mirror)
			)
		)
		(duplicate_pad_numbers_are_jumpers no)
		(fp_line
			(start 0.7874 0.4064)
			(end 0.7874 -0.4064)
			(stroke
				(width 0.1524)
				(type default)
			)
			(layer "B.SilkS")
		)
		(fp_line
			(start 0.7874 -0.4064)
			(end -0.7874 -0.4064)
			(stroke
				(width 0.1524)
				(type default)
			)
			(layer "B.SilkS")
		)
		(fp_line
			(start -0.7874 0.4064)
			(end 0.7874 0.4064)
			(stroke
				(width 0.1524)
				(type default)
			)
			(layer "B.SilkS")
		)
		(fp_line
			(start -0.7874 -0.4064)
			(end -0.7874 0.4064)
			(stroke
				(width 0.1524)
				(type default)
			)
			(layer "B.SilkS")
		)
		(fp_line
			(start 0.67945 0.3048)
			(end 0.67945 -0.305054)
			(stroke
				(width 0.1)
				(type default)
			)
			(layer "B.Fab")
		)
		(fp_line
			(start 0.67945 -0.305054)
			(end 0.12065 -0.305054)
			(stroke
				(width 0.1)
				(type default)
			)
			(layer "B.Fab")
		)
		(fp_line
			(start 0.12065 0.3048)
			(end 0.67945 0.3048)
			(stroke
				(width 0.1)
				(type default)
			)
			(layer "B.Fab")
		)
		(fp_line
			(start 0.12065 0.2794)
			(end 0.12065 0.3048)
			(stroke
				(width 0.1)
				(type default)
			)
			(layer "B.Fab")
		)
		(fp_line
			(start 0.12065 -0.2794)
			(end -0.12065 -0.2794)
			(stroke
				(width 0.1)
				(type default)
			)
			(layer "B.Fab")
		)
		(fp_line
			(start 0.12065 -0.305054)
			(end 0.12065 -0.2794)
			(stroke
				(width 0.1)
				(type default)
			)
			(layer "B.Fab")
		)
		(fp_line
			(start -0.120396 0.3048)
			(end -0.120396 0.2794)
			(stroke
				(width 0.1)
				(type default)
			)
			(layer "B.Fab")
		)
		(fp_line
			(start -0.120396 0.2794)
			(end 0.12065 0.2794)
			(stroke
				(width 0.1)
				(type default)
			)
			(layer "B.Fab")
		)
		(fp_line
			(start -0.12065 -0.2794)
			(end -0.12065 -0.3048)
			(stroke
				(width 0.1)
				(type default)
			)
			(layer "B.Fab")
		)
		(fp_line
			(start -0.12065 -0.3048)
			(end -0.67945 -0.3048)
			(stroke
				(width 0.1)
				(type default)
			)
			(layer "B.Fab")
		)
		(fp_line
			(start -0.67945 0.3048)
			(end -0.120396 0.3048)
			(stroke
				(width 0.1)
				(type default)
			)
			(layer "B.Fab")
		)
		(fp_line
			(start -0.67945 -0.3048)
			(end -0.67945 0.3048)
			(stroke
				(width 0.1)
				(type default)
			)
			(layer "B.Fab")
		)
		(pad "1" smd circle
			(at 0.40005 0)
			(size 0 0)
			(layers "B.Cu" "B.Mask" "B.Paste")
			(net "P3V3_AUX")
		)
		(pad "2" smd circle
			(at -0.40005 0)
			(size 0 0)
			(layers "B.Cu" "B.Mask" "B.Paste")
			(net "GND")
		)
	)
)
